G04 ================== begin FILE IDENTIFICATION RECORD ==================*
G04 Layout Name:  12004-1.brd*
G04 Film Name:    GOLD_T*
G04 File Format:  Gerber RS274X*
G04 File Origin:  Cadence Allegro 16.2-S033*
G04 Origin Date:  Tue Oct 16 17:03:28 2012*
G04 *
G04 Layer:  DRAWING FORMAT/LAYER_GOLD_T*
G04 Layer:  DRAWING FORMAT/LAYER_PCB_STORY*
G04 Layer:  BOARD GEOMETRY/GOLDEN_TOP*
G04 Layer:  BOARD GEOMETRY/PANEL_OUTLINE*
G04 *
G04 Offset:    (0.00 0.00)*
G04 Mirror:    No*
G04 Mode:      Positive*
G04 Rotation:  0*
G04 FullContactRelief:  No*
G04 UndefLineWidth:     6.00*
G04 ================== end FILE IDENTIFICATION RECORD ====================*
%FSLAX35Y35*MOIN*%
%IR0*IPPOS*OFA0.00000B0.00000*MIA0B0*SFA1.00000B1.00000*%
%ADD10C,.02*%
%ADD11C,.006*%
G75*
%LPD*%
G75*
G36*
G01X773215Y660133D02*
Y328133D01*
X795315D01*
Y660133D01*
X773215D01*
G37*
G36*
G01X773115Y817533D02*
Y737633D01*
X795315D01*
Y817533D01*
X773115D01*
G37*
G54D10*
G01X-771361Y-182763D02*
Y-262763D01*
G01Y-218263D02*
X373639D01*
G01X-771361Y-262763D02*
X373639D01*
G01X-775361Y-166763D02*
G02I-12000J0D01*
G01X-780511D02*
G02I-6850J0D01*
G01X-787361Y-182763D02*
Y-150763D01*
G01X-771361Y-166763D02*
X-803361D01*
G01X-771361Y-182763D02*
X373639D01*
G01X-413861D02*
Y-262763D01*
G01X-276361Y-182763D02*
Y-262763D01*
G01X-161361Y-182763D02*
Y-262763D01*
G01X6139Y-182763D02*
Y-262763D01*
G01X176139Y-182763D02*
Y-262763D01*
G01X373639Y-182763D02*
Y-262763D01*
G01X401639Y-166763D02*
G02I-12000J0D01*
G01X396489D02*
G02I-6850J0D01*
G01X389639Y-182763D02*
Y-150763D01*
G01X405639Y-166763D02*
X373639D01*
G54D11*
G01X-1003937Y-3937D02*
G03X-1000000Y-7874I3937J0D01*
G01X-1031496Y-31496D02*
G03X-1027559Y-35433I3937J0D01*
G01X-986221Y-7874D02*
G03Y0I0J3937D01*
G01Y-7874D02*
X-1000000D01*
G01X-1027559Y-35433D02*
X791338D01*
G01X-1031496Y95866D02*
Y-31496D01*
G01X-996063Y3937D02*
G03X-992126Y0I3937J0D01*
G01X-996063Y39370D02*
G03X-1003937I-3937J0D01*
G01X-996063Y3937D02*
G03X-992126Y0I3937J0D01*
G01D02*
X-318898D01*
G01D02*
X-992126D01*
G01X-955512D02*
X-986221D01*
G01X-996063Y3937D02*
Y103740D01*
G01Y39370D02*
Y70079D01*
G01X-1003937Y-3937D02*
Y39370D01*
G01X-1027559Y99803D02*
G03X-1031496Y95866I0J-3937D01*
G01X-1003937D02*
G03X-1007874Y99803I-3937J0D01*
G01X-996063Y103740D02*
G03X-1000000Y107677I-3937J0D01*
G01X-1003937Y70079D02*
G03X-996063I3937J0D01*
G01X-1029528Y107677D02*
X-1000000D01*
G01X-1007874Y99803D02*
X-1027559D01*
G01X-1003937Y70079D02*
Y95866D01*
G01X-1031496Y109646D02*
X-1029528Y107677D01*
G01X-1031496Y109646D02*
Y134055D01*
G01X-1002166Y136024D02*
G03Y143504I0J3740D01*
G01X-1000000Y187599D02*
G03X-996063Y191536I0J3937D01*
G01X-1029528Y187599D02*
X-1000000D01*
G01X-1029528Y143504D02*
X-1002166D01*
G01X-1029528Y136024D02*
X-1002166D01*
G01X-1029528D02*
X-1031496Y134055D01*
G01X-1029528Y187599D02*
X-1031496Y185630D01*
G01Y145473D02*
X-1029528Y143504D01*
G01X-996063Y261221D02*
Y191536D01*
G01X-1031496Y145473D02*
Y185630D01*
G01X-996063Y261221D02*
G03X-1000000Y265158I-3937J0D01*
G01X-1029528D02*
X-1000000D01*
G01X-1031496Y267126D02*
X-1029528Y265158D01*
G01X-1031496Y267126D02*
Y543504D01*
G01X-1002166Y545473D02*
G03Y552953I0J3740D01*
G01X-1029528D02*
X-1002166D01*
G01X-1029528Y545473D02*
X-1002166D01*
G01X-1031496Y554922D02*
X-1029528Y552953D01*
G01Y545473D02*
X-1031496Y543504D01*
G01Y554922D02*
Y595079D01*
G01X-1007874Y604922D02*
G03X-1003937Y608859I0J3937D01*
G01X-1031496D02*
G03X-1027559Y604922I3937J0D01*
G01X-1000000Y597048D02*
G03X-996063Y600985I0J3937D01*
G01X-1027559Y604922D02*
X-1007874D01*
G01X-1029528Y597048D02*
X-1000000D01*
G01X-1029528D02*
X-1031496Y595079D01*
G01X-996063Y921260D02*
Y600985D01*
G01X-1003937Y608859D02*
Y708662D01*
G01X-1031496Y956693D02*
Y608859D01*
G01X-1003937Y739370D02*
G03X-996063I3937J0D01*
G01Y708662D02*
G03X-1003937I-3937J0D01*
G01X-996063D02*
Y739370D01*
G01X-1003937D02*
Y929134D01*
G01X-992126Y925197D02*
G03X-996063Y921260I0J-3937D01*
G01X-1000000Y933071D02*
G03X-1003937Y929134I0J-3937D01*
G01X-986221Y925197D02*
G03Y933071I0J3937D01*
G01X-1027559Y960630D02*
G03X-1031496Y956693I0J-3937D01*
G01X-992126Y925197D02*
G03X-996063Y921260I0J-3937D01*
G01X791338Y960630D02*
X-1027559D01*
G01X-1000000Y933071D02*
X-986221D01*
G01X-992126Y925197D02*
X-240158D01*
G01X-986221D02*
X-955512D01*
G01X-992126D02*
X-240158D01*
G01X-955512Y0D02*
G03Y-7874I0J-3937D01*
G01X-769685D02*
X-955512D01*
G01Y933071D02*
G03Y925197I0J-3937D01*
G01Y933071D02*
X-750000D01*
G01X-769685Y-7874D02*
G03Y0I0J3937D01*
G01X-738977D02*
X-769685D01*
G01X-755164Y-252763D02*
Y-235263D01*
G01X-746868D02*
X-755164Y-246055D01*
G01X-745558Y-252763D02*
X-751453Y-241097D01*
G01X-737883Y-252763D02*
Y-235263D01*
X-727839Y-252763D01*
Y-235263D01*
G01X-715361Y-252763D02*
X-717108Y-252471D01*
X-718636Y-251305D01*
X-719946Y-249555D01*
X-720820Y-247513D01*
X-721256Y-245180D01*
Y-242846D01*
X-720820Y-240513D01*
X-719946Y-238471D01*
X-718636Y-236722D01*
X-717108Y-235555D01*
X-715361Y-235263D01*
X-713615Y-235555D01*
X-712086Y-236722D01*
X-710776Y-238471D01*
X-709902Y-240513D01*
X-709466Y-242846D01*
Y-245180D01*
X-709902Y-247513D01*
X-710776Y-249555D01*
X-712086Y-251305D01*
X-713615Y-252471D01*
X-715361Y-252763D01*
G01X-702446D02*
X-693276Y-235263D01*
G01X-702446D02*
X-693276Y-252763D01*
G01X-658494D02*
X-667228D01*
Y-235263D01*
X-658494D01*
G01X-661988Y-243721D02*
X-667228D01*
G01X-649946Y-252763D02*
X-640776Y-235263D01*
G01X-649946D02*
X-640776Y-252763D01*
G01X-632228D02*
Y-235263D01*
X-626988D01*
X-625241Y-236138D01*
X-623931Y-238180D01*
X-623494Y-240513D01*
X-623931Y-242846D01*
X-625023Y-244596D01*
X-626988Y-245472D01*
X-632228D01*
G01X-615820Y-252763D02*
X-610361Y-235263D01*
X-604902Y-252763D01*
G01X-606868Y-246638D02*
X-613855D01*
G01X-597883Y-252763D02*
Y-235263D01*
X-587839Y-252763D01*
Y-235263D01*
G01X-580164Y-252763D02*
Y-235263D01*
X-575798D01*
X-574051Y-236138D01*
X-572741Y-237305D01*
X-571649Y-239054D01*
X-570776Y-241097D01*
X-570558Y-244013D01*
X-570776Y-246930D01*
X-571649Y-248972D01*
X-572741Y-250722D01*
X-574051Y-251888D01*
X-575798Y-252763D01*
X-580164D01*
G01X-553494D02*
X-562228D01*
Y-235263D01*
X-553494D01*
G01X-556988Y-243721D02*
X-562228D01*
G01X-544728Y-252763D02*
Y-235263D01*
X-539269D01*
X-537523Y-236138D01*
X-536431Y-237305D01*
X-535994Y-239638D01*
X-536431Y-241972D01*
X-537741Y-243430D01*
X-539269Y-244305D01*
X-544728D01*
G01X-539269D02*
X-535994Y-252763D01*
G01X-503615Y-243430D02*
X-502741Y-242555D01*
X-502086Y-241097D01*
X-501649Y-239054D01*
X-502086Y-237305D01*
X-502959Y-236138D01*
X-504488Y-235263D01*
X-510383D01*
Y-252763D01*
X-503178D01*
X-501649Y-251597D01*
X-500776Y-249846D01*
X-500339Y-247805D01*
X-500776Y-245763D01*
X-502086Y-244013D01*
X-503615Y-243430D01*
X-510383D01*
G01X-487861Y-252763D02*
X-489608Y-252471D01*
X-491136Y-251305D01*
X-492446Y-249555D01*
X-493320Y-247513D01*
X-493756Y-245180D01*
Y-242846D01*
X-493320Y-240513D01*
X-492446Y-238471D01*
X-491136Y-236722D01*
X-489608Y-235555D01*
X-487861Y-235263D01*
X-486115Y-235555D01*
X-484586Y-236722D01*
X-483276Y-238471D01*
X-482402Y-240513D01*
X-481966Y-242846D01*
Y-245180D01*
X-482402Y-247513D01*
X-483276Y-249555D01*
X-484586Y-251305D01*
X-486115Y-252471D01*
X-487861Y-252763D01*
G01X-475820D02*
X-470361Y-235263D01*
X-464902Y-252763D01*
G01X-466868Y-246638D02*
X-473855D01*
G01X-457228Y-252763D02*
Y-235263D01*
X-451769D01*
X-450023Y-236138D01*
X-448931Y-237305D01*
X-448494Y-239638D01*
X-448931Y-241972D01*
X-450241Y-243430D01*
X-451769Y-244305D01*
X-457228D01*
G01X-451769D02*
X-448494Y-252763D01*
G01X-440164D02*
Y-235263D01*
X-435798D01*
X-434051Y-236138D01*
X-432741Y-237305D01*
X-431649Y-239054D01*
X-430776Y-241097D01*
X-430558Y-244013D01*
X-430776Y-246930D01*
X-431649Y-248972D01*
X-432741Y-250722D01*
X-434051Y-251888D01*
X-435798Y-252763D01*
X-440164D01*
G01X-738977Y0D02*
G03Y-7874I0J-3937D01*
G01X-522835D02*
X-738977D01*
G01X-719292Y933071D02*
G03Y925197I0J-3937D01*
G01X-750000D02*
G03Y933071I0J3937D01*
G01X-719292D02*
X-512992D01*
G01X-750000Y925197D02*
X-719292D01*
G01X-633538Y-207763D02*
Y-190263D01*
X-627861Y-204846D01*
X-622184Y-190263D01*
Y-207763D01*
G01X-610361D02*
X-611671Y-207471D01*
X-612981Y-206305D01*
X-613855Y-204263D01*
X-614291Y-201930D01*
X-613855Y-199596D01*
X-612981Y-197555D01*
X-611671Y-196388D01*
X-610361Y-196097D01*
X-609051Y-196388D01*
X-607741Y-197555D01*
X-606868Y-199596D01*
X-606649Y-201930D01*
X-606868Y-204263D01*
X-607741Y-206305D01*
X-609051Y-207471D01*
X-610361Y-207763D01*
G01X-588931Y-190263D02*
Y-207763D01*
G01Y-205139D02*
X-589804Y-206597D01*
X-591115Y-207471D01*
X-592643Y-207763D01*
X-594389Y-207180D01*
X-595699Y-205722D01*
X-596573Y-203972D01*
X-596791Y-201930D01*
X-596573Y-199888D01*
X-595699Y-198138D01*
X-594389Y-196680D01*
X-592643Y-196097D01*
X-591115Y-196388D01*
X-590023Y-196972D01*
X-588931Y-198138D01*
G01X-578636Y-199888D02*
X-571649D01*
X-572304Y-197846D01*
X-573396Y-196680D01*
X-574924Y-196097D01*
X-576453Y-196388D01*
X-577763Y-197263D01*
X-578636Y-199305D01*
X-579073Y-201055D01*
Y-202805D01*
X-578636Y-204555D01*
X-577544Y-206305D01*
X-576234Y-207471D01*
X-574706Y-207763D01*
X-573178Y-207180D01*
X-571649Y-205430D01*
G01X-557861Y-207763D02*
Y-190263D01*
G01X-522835Y-7874D02*
G03Y0I0J3937D01*
G01X-492126D02*
G03Y-7874I0J-3937D01*
G01X-365355D02*
X-492126D01*
G01Y0D02*
X-522835D01*
G01X-482284Y933071D02*
G03Y925197I0J-3937D01*
G01X-512992D02*
G03Y933071I0J3937D01*
G01Y925197D02*
X-482284D01*
G01Y933071D02*
X-316142D01*
G01X-380161Y-252763D02*
Y-235263D01*
X-382781Y-238763D01*
G01Y-252763D02*
X-377541D01*
G01X-366809Y-238180D02*
X-365499Y-236430D01*
X-363971Y-235555D01*
X-362224Y-235263D01*
X-360041Y-235846D01*
X-358513Y-237305D01*
X-358076Y-239054D01*
X-358294Y-240805D01*
X-359168Y-242263D01*
X-363534Y-245180D01*
X-365499Y-247221D01*
X-366809Y-250139D01*
X-367246Y-252763D01*
X-358076D01*
G01X-345161Y-235263D02*
X-346908Y-235846D01*
X-348218Y-237305D01*
X-349091Y-239054D01*
X-349746Y-241388D01*
X-349964Y-244013D01*
X-349746Y-246638D01*
X-349091Y-248972D01*
X-348218Y-250722D01*
X-346908Y-252180D01*
X-345161Y-252763D01*
X-343415Y-252180D01*
X-342104Y-250722D01*
X-341231Y-248972D01*
X-340576Y-246638D01*
X-340358Y-244013D01*
X-340576Y-241388D01*
X-341231Y-239054D01*
X-342104Y-237305D01*
X-343415Y-235846D01*
X-345161Y-235263D01*
G01X-327661D02*
X-329408Y-235846D01*
X-330718Y-237305D01*
X-331591Y-239054D01*
X-332246Y-241388D01*
X-332464Y-244013D01*
X-332246Y-246638D01*
X-331591Y-248972D01*
X-330718Y-250722D01*
X-329408Y-252180D01*
X-327661Y-252763D01*
X-325915Y-252180D01*
X-324604Y-250722D01*
X-323731Y-248972D01*
X-323076Y-246638D01*
X-322858Y-244013D01*
X-323076Y-241388D01*
X-323731Y-239054D01*
X-324604Y-237305D01*
X-325915Y-235846D01*
X-327661Y-235263D01*
G01X-307541Y-252763D02*
Y-235263D01*
X-315620Y-247805D01*
X-304702D01*
G01X-393278Y-207763D02*
Y-190263D01*
X-388038D01*
X-386291Y-191138D01*
X-384981Y-193180D01*
X-384544Y-195513D01*
X-384981Y-197846D01*
X-386073Y-199596D01*
X-388038Y-200472D01*
X-393278D01*
G01X-366608Y-191722D02*
X-367918Y-190846D01*
X-369446Y-190263D01*
X-371193D01*
X-373158Y-191138D01*
X-374686Y-192596D01*
X-375778Y-194347D01*
X-376651Y-197263D01*
X-376870Y-199888D01*
X-376433Y-202513D01*
X-375778Y-204263D01*
X-374468Y-206013D01*
X-372939Y-207180D01*
X-371411Y-207763D01*
X-369883D01*
X-368354Y-207180D01*
X-367044Y-206305D01*
X-365952Y-205139D01*
G01X-352165Y-198430D02*
X-351291Y-197555D01*
X-350636Y-196097D01*
X-350199Y-194054D01*
X-350636Y-192305D01*
X-351509Y-191138D01*
X-353038Y-190263D01*
X-358933D01*
Y-207763D01*
X-351728D01*
X-350199Y-206597D01*
X-349326Y-204846D01*
X-348889Y-202805D01*
X-349326Y-200763D01*
X-350636Y-199013D01*
X-352165Y-198430D01*
X-358933D01*
G01X-342961Y-213596D02*
X-329861D01*
G01X-323933Y-207763D02*
Y-190263D01*
X-313889Y-207763D01*
Y-190263D01*
G01X-301411Y-207763D02*
X-303158Y-207471D01*
X-304686Y-206305D01*
X-305996Y-204555D01*
X-306870Y-202513D01*
X-307306Y-200180D01*
Y-197846D01*
X-306870Y-195513D01*
X-305996Y-193471D01*
X-304686Y-191722D01*
X-303158Y-190555D01*
X-301411Y-190263D01*
X-299665Y-190555D01*
X-298136Y-191722D01*
X-296826Y-193471D01*
X-295952Y-195513D01*
X-295516Y-197846D01*
Y-200180D01*
X-295952Y-202513D01*
X-296826Y-204555D01*
X-298136Y-206305D01*
X-299665Y-207471D01*
X-301411Y-207763D01*
G01X-365355Y-7874D02*
G03Y0I0J3937D01*
G01X-334646D02*
X-365355D01*
G01X-311024Y-7874D02*
G03X-307087Y-3937I0J3937D01*
G01X-334646Y0D02*
G03Y-7874I0J-3937D01*
G01X-311024D02*
X-334646D01*
G01X-318898Y0D02*
G03X-314961Y3937I0J3937D01*
G01X-274410Y31595D02*
G03X-270473Y35532I0J3937D01*
G01X-303150Y31595D02*
G03X-307087Y27658I0J-3937D01*
G01X-318898Y0D02*
G03X-314961Y3937I0J3937D01*
G01X-307087Y27658D02*
Y-3937D01*
G01X-314961Y133859D02*
Y3937D01*
G01Y133859D02*
Y3937D01*
G01X-274410Y31595D02*
X-303150D01*
G01X-311024Y137796D02*
G03X-314961Y133859I0J-3937D01*
G01X-311024Y137796D02*
G03X-314961Y133859I0J-3937D01*
G01X-240158Y137796D02*
X-311024D01*
G01X-240158D02*
X-311024D01*
G01X-285433Y933071D02*
G03Y925197I0J-3937D01*
G01X-316142D02*
G03Y933071I0J3937D01*
G01X-285433D02*
X-224410D01*
G01X-316142Y925197D02*
X-285433D01*
G01X-218861Y-252763D02*
Y-235263D01*
X-221481Y-238763D01*
G01Y-252763D02*
X-216241D01*
G01X-250570Y-190263D02*
X-245111Y-207763D01*
X-239652Y-190263D01*
G01X-223244Y-207763D02*
X-231978D01*
Y-190263D01*
X-223244D01*
G01X-226738Y-198721D02*
X-231978D01*
G01X-214478Y-207763D02*
Y-190263D01*
X-209019D01*
X-207273Y-191138D01*
X-206181Y-192305D01*
X-205744Y-194638D01*
X-206181Y-196972D01*
X-207491Y-198430D01*
X-209019Y-199305D01*
X-214478D01*
G01X-209019D02*
X-205744Y-207763D01*
G01X-192611Y-208346D02*
X-193048Y-208055D01*
Y-207471D01*
X-192611Y-207180D01*
X-192174Y-207471D01*
Y-208055D01*
X-192611Y-208346D01*
G01X-270473Y125985D02*
Y35532D01*
G01X-266536Y129922D02*
G03X-270473Y125985I0J-3937D01*
G01X-260630Y129922D02*
G03Y137796I0J3937D01*
G01X-244882D02*
G03Y129922I0J-3937D01*
G01X-240158D02*
G03X-228347Y141733I0J11811D01*
G01X-260630Y129922D02*
X-266536D01*
G01X-240158D02*
X-244882D01*
G01X-240158Y137796D02*
G03X-236221Y141733I0J3937D01*
G01X-240158Y137796D02*
G03X-236221Y141733I0J3937D01*
G01X-228347Y368701D02*
Y141733D01*
G01X-236221Y413386D02*
Y141733D01*
G01X-244882Y137796D02*
X-260630D01*
G01X-204725Y409449D02*
G03X-208662Y405512I0J-3937D01*
G01X-232284Y417323D02*
G03X-236221Y413386I0J-3937D01*
G01X-232284Y417323D02*
G03X-236221Y413386I0J-3937D01*
G01X-212599Y372638D02*
G03X-208662Y376575I0J3937D01*
G01X-224410Y372638D02*
G03X-228347Y368701I0J-3937D01*
G01X-181103Y409449D02*
X-204725D01*
G01X-212599Y372638D02*
X-224410D01*
G01X-208662Y405512D02*
Y376575D01*
G01X-232284Y417323D02*
X-181103D01*
G01X-232284D02*
X-181103D01*
G01X-236221Y716536D02*
G03X-232284Y712599I3937J0D01*
G01X-224410Y724410D02*
G03X-220473Y720473I3937J0D01*
G01X-236221Y716536D02*
G03X-232284Y712599I3937J0D01*
G01X-220473Y720473D02*
X-96418D01*
G01Y712599D02*
X-232284D01*
G01X-96418D02*
X-232284D01*
G01X-224410Y933071D02*
Y724410D01*
G01X-236221Y921260D02*
Y716536D01*
G01Y921260D02*
G03X-240158Y925197I-3937J0D01*
G01X-236221Y921260D02*
G03X-240158Y925197I-3937J0D01*
G01X-143740Y216536D02*
G03X-139803Y212599I3937J0D01*
G01X-143740Y262205D02*
G03X-151614I-3937J0D01*
G01X-143740Y216536D02*
G03X-139803Y212599I3937J0D01*
G01X-151614Y216536D02*
G03X-139803Y204725I11811J0D01*
G01X-143740Y262205D02*
Y292914D01*
G01Y338583D02*
Y216536D01*
G01Y338583D02*
Y216536D01*
G01X-151614D02*
Y262205D01*
G01X-139803Y212599D02*
X-3937D01*
G01X-139803D02*
X-3937D01*
G01X-15748Y204725D02*
X-139803D01*
G01Y342520D02*
G03X-143740Y338583I0J-3937D01*
G01X-139803Y342520D02*
G03X-143740Y338583I0J-3937D01*
G01X-139803Y350394D02*
G03X-151614Y338583I0J-11811D01*
G01Y292914D02*
G03X-143740I3937J0D01*
G01X-151614D02*
Y338583D01*
G01X-62992Y342520D02*
X-139803D01*
G01X-62992D02*
X-139803D01*
G01X-181103Y409449D02*
G03X-169292Y421260I0J11811D01*
G01X-139803Y350394D02*
X-70866D01*
G01X-177166Y467717D02*
G03X-169292I3937J0D01*
G01X-181103Y417323D02*
G03X-177166Y421260I0J3937D01*
G01X-169292Y437008D02*
G03X-177166I-3937J0D01*
G01X-181103Y417323D02*
G03X-177166Y421260I0J3937D01*
G01X-169292Y437008D02*
Y421260D01*
G01Y570866D02*
Y467717D01*
G01X-177166Y421260D02*
Y578740D01*
G01Y421260D02*
Y578740D01*
G01Y467717D02*
Y437008D01*
G01X-173229Y582677D02*
G03X-177166Y578740I0J-3937D01*
G01X-165355Y574803D02*
G03X-169292Y570866I0J-3937D01*
G01X-173229Y582677D02*
G03X-177166Y578740I0J-3937D01*
G01X-173229Y582677D02*
X-96418D01*
G01X-173229D02*
X-96418D01*
G01Y574803D02*
X-165355D01*
G01X-125778Y-190263D02*
Y-207763D01*
X-117044D01*
G01X-99981D02*
Y-196097D01*
G01Y-198138D02*
X-100854Y-196972D01*
X-102165Y-196388D01*
X-103693Y-196097D01*
X-105221Y-196680D01*
X-106531Y-197846D01*
X-107405Y-199596D01*
X-107841Y-201930D01*
X-107405Y-204263D01*
X-106531Y-206013D01*
X-105221Y-207180D01*
X-103693Y-207763D01*
X-102165Y-207471D01*
X-100854Y-206597D01*
X-99981Y-205430D01*
G01X-90996Y-213013D02*
X-89686Y-213596D01*
X-87939Y-213013D01*
X-86848Y-211847D01*
X-85974Y-210388D01*
X-84665Y-205722D01*
X-81826Y-196097D01*
G01X-88813D02*
X-84665Y-205722D01*
G01X-72186Y-199888D02*
X-65199D01*
X-65854Y-197846D01*
X-66946Y-196680D01*
X-68474Y-196097D01*
X-70003Y-196388D01*
X-71313Y-197263D01*
X-72186Y-199305D01*
X-72623Y-201055D01*
Y-202805D01*
X-72186Y-204555D01*
X-71094Y-206305D01*
X-69784Y-207471D01*
X-68256Y-207763D01*
X-66728Y-207180D01*
X-65199Y-205430D01*
G01X-54468Y-207763D02*
Y-196097D01*
G01Y-198430D02*
X-53376Y-197263D01*
X-52284Y-196388D01*
X-50756Y-196097D01*
X-49665Y-196388D01*
X-48354Y-197263D01*
G01X-37186Y-205722D02*
X-36094Y-206888D01*
X-34566Y-207763D01*
X-33256D01*
X-31946Y-207180D01*
X-31073Y-206305D01*
X-30636Y-205139D01*
X-30854Y-203388D01*
X-31728Y-202513D01*
X-35658Y-200763D01*
X-36531Y-198721D01*
X-36094Y-197263D01*
X-35221Y-196388D01*
X-33911Y-196097D01*
X-32601Y-196388D01*
X-31291Y-197263D01*
G01X-62992Y342520D02*
G03X-59055Y346457I0J3937D01*
G01X-62992Y342520D02*
G03X-59055Y346457I0J3937D01*
G01X-70866Y350394D02*
G03X-66929Y354331I0J3937D01*
G01D02*
Y457481D01*
G01Y488189D02*
G03X-59055I3937J0D01*
G01Y457481D02*
G03X-66929I-3937J0D01*
G01X-55118Y515748D02*
G03X-66929Y503937I0J-11811D01*
G01Y488189D02*
Y503937D01*
G01X-96418Y582677D02*
G03X-92481Y586615I0J3937D01*
G01X-96418Y582677D02*
G03X-92481Y586615I0J3937D01*
G01X-96418Y574803D02*
G03X-84607Y586615I0J11811D01*
G01Y632284D02*
Y586615D01*
G01X-92481D02*
Y708662D01*
G01Y586615D02*
Y708662D01*
G01Y662992D02*
G03X-84607I3937J0D01*
G01Y632284D02*
G03X-92481I-3937J0D01*
G01X-84607Y708662D02*
Y662992D01*
G01X-92481D02*
Y632284D01*
G01Y708662D02*
G03X-96418Y712599I-3937J0D01*
G01X-92481Y708662D02*
G03X-96418Y712599I-3937J0D01*
G01X-84607Y708662D02*
G03X-96418Y720473I-11811J0D01*
G01X-11811Y-3937D02*
G03X-7874Y-7874I3937J0D01*
G01X31496D02*
X-7874D01*
G01X0Y3937D02*
G03X3937Y0I3937J0D01*
G01X0Y3937D02*
G03X3937Y0I3937J0D01*
G01X0Y3937D02*
Y208662D01*
G01X-11811Y-3937D02*
Y200788D01*
G01X755905Y0D02*
X3937D01*
G01X755905D02*
X3937D01*
G01X-11811Y200788D02*
G03X-15748Y204725I-3937J0D01*
G01X0Y208662D02*
G03X-3937Y212599I-3937J0D01*
G01X0Y208662D02*
G03X-3937Y212599I-3937J0D01*
G01X-59055Y503937D02*
Y346457D01*
G01Y503937D02*
Y346457D01*
G01Y488189D02*
Y457481D01*
G01X-23622Y552559D02*
G03X-27559Y548622I0J-3937D01*
G01X-11811Y552559D02*
G03X-7874Y556496I0J3937D01*
G01X-3937Y507874D02*
G03X0Y511811I0J3937D01*
G01X-3937Y507874D02*
G03X0Y511811I0J3937D01*
G01X-55118Y507874D02*
G03X-59055Y503937I0J-3937D01*
G01X-31496Y515748D02*
G03X-27559Y519685I0J3937D01*
G01X-55118Y507874D02*
G03X-59055Y503937I0J-3937D01*
G01X-23622Y552559D02*
X-11811D01*
G01X0Y511811D02*
Y783465D01*
G01X-27559Y519685D02*
Y548622D01*
G01X-55118Y515748D02*
X-31496D01*
G01X-3937Y507874D02*
X-55118D01*
G01X-3937D02*
X-55118D01*
G01X-7874Y556496D02*
Y783465D01*
G01X3937Y787402D02*
G03X0Y783465I0J-3937D01*
G01X3937Y787402D02*
G03X0Y783465I0J-3937D01*
G01X3937Y795276D02*
G03X-7874Y783465I0J-11811D01*
G01X3937Y795276D02*
X8661D01*
G01X3937Y787402D02*
X74803D01*
G01X3937D02*
X74803D01*
G01X51772Y-235263D02*
Y-252763D01*
X60506D01*
G01X68836Y-235263D02*
Y-247805D01*
X69709Y-250430D01*
X71456Y-252180D01*
X73639Y-252763D01*
X75822Y-252180D01*
X77569Y-250430D01*
X78442Y-247805D01*
Y-235263D01*
G01X95942Y-236722D02*
X94632Y-235846D01*
X93104Y-235263D01*
X91357D01*
X89392Y-236138D01*
X87864Y-237596D01*
X86772Y-239347D01*
X85899Y-242263D01*
X85680Y-244888D01*
X86117Y-247513D01*
X86772Y-249263D01*
X88082Y-251013D01*
X89611Y-252180D01*
X91139Y-252763D01*
X92667D01*
X94196Y-252180D01*
X95506Y-251305D01*
X96598Y-250139D01*
G01X103836Y-252763D02*
Y-235263D01*
G01X112132D02*
X103836Y-246055D01*
G01X113442Y-252763D02*
X107547Y-241097D01*
G01X126139Y-252763D02*
Y-244888D01*
X121772Y-235263D01*
G01X130506D02*
X126139Y-244888D01*
G01X25086Y-207763D02*
Y-190263D01*
X29452D01*
X31199Y-191138D01*
X32509Y-192305D01*
X33601Y-194054D01*
X34474Y-196097D01*
X34692Y-199013D01*
X34474Y-201930D01*
X33601Y-203972D01*
X32509Y-205722D01*
X31199Y-206888D01*
X29452Y-207763D01*
X25086D01*
G01X44114Y-199888D02*
X51101D01*
X50446Y-197846D01*
X49354Y-196680D01*
X47826Y-196097D01*
X46297Y-196388D01*
X44987Y-197263D01*
X44114Y-199305D01*
X43677Y-201055D01*
Y-202805D01*
X44114Y-204555D01*
X45206Y-206305D01*
X46516Y-207471D01*
X48044Y-207763D01*
X49572Y-207180D01*
X51101Y-205430D01*
G01X61614Y-205722D02*
X62706Y-206888D01*
X64234Y-207763D01*
X65544D01*
X66854Y-207180D01*
X67727Y-206305D01*
X68164Y-205139D01*
X67946Y-203388D01*
X67072Y-202513D01*
X63142Y-200763D01*
X62269Y-198721D01*
X62706Y-197263D01*
X63579Y-196388D01*
X64889Y-196097D01*
X66199Y-196388D01*
X67509Y-197263D01*
G01X82389Y-196097D02*
Y-207763D01*
G01Y-191430D02*
X81952Y-191138D01*
Y-190555D01*
X82389Y-190263D01*
X82826Y-190555D01*
Y-191138D01*
X82389Y-191430D01*
G01X96832Y-212138D02*
X98361Y-213305D01*
X100107Y-213596D01*
X101635Y-213305D01*
X102946Y-211847D01*
X103819Y-209805D01*
Y-196097D01*
G01Y-198430D02*
X102946Y-197263D01*
X101635Y-196388D01*
X100107Y-196097D01*
X98361Y-196680D01*
X97269Y-197846D01*
X96395Y-199888D01*
X95959Y-201930D01*
X96177Y-203680D01*
X97051Y-205722D01*
X98361Y-207180D01*
X100107Y-207763D01*
X101417Y-207471D01*
X102946Y-206305D01*
X103819Y-205139D01*
G01X113677Y-207763D02*
Y-196097D01*
G01Y-199013D02*
X114551Y-197555D01*
X115861Y-196388D01*
X117607Y-196097D01*
X119135Y-196388D01*
X120446Y-197555D01*
X121101Y-199596D01*
Y-207763D01*
G01X131614Y-199888D02*
X138601D01*
X137946Y-197846D01*
X136854Y-196680D01*
X135326Y-196097D01*
X133797Y-196388D01*
X132487Y-197263D01*
X131614Y-199305D01*
X131177Y-201055D01*
Y-202805D01*
X131614Y-204555D01*
X132706Y-206305D01*
X134016Y-207471D01*
X135544Y-207763D01*
X137072Y-207180D01*
X138601Y-205430D01*
G01X149332Y-207763D02*
Y-196097D01*
G01Y-198430D02*
X150424Y-197263D01*
X151516Y-196388D01*
X153044Y-196097D01*
X154135Y-196388D01*
X155446Y-197263D01*
G01X62204Y0D02*
G03Y-7874I0J-3937D01*
G01X31496D02*
G03Y0I0J3937D01*
G01X267716Y-7874D02*
X62204D01*
G01Y0D02*
X31496D01*
G01X74803Y787402D02*
G03X78740Y791339I0J3937D01*
G01X30315Y795276D02*
G03X34252Y799213I0J3937D01*
G01X24409Y795276D02*
G03Y787402I0J-3937D01*
G01X8661D02*
G03Y795276I0J3937D01*
G01X74803Y787402D02*
G03X78740Y791339I0J3937D01*
G01X24409Y795276D02*
X30315D01*
G01X24409Y787402D02*
X8661D01*
G01X34252Y799213D02*
Y889666D01*
G01X38189Y893603D02*
G03X34252Y889666I0J-3937D01*
G01X66929Y893603D02*
G03X70866Y897540I0J3937D01*
G01X38189Y893603D02*
X66929D01*
G01X70866Y897540D02*
Y929134D01*
G01X74803Y933071D02*
G03X70866Y929134I0J-3937D01*
G01X74803Y933071D02*
X88582D01*
G01X78740Y791339D02*
Y921260D01*
G01Y791339D02*
Y921260D01*
G01X119291Y933071D02*
G03Y925197I0J-3937D01*
G01X82677D02*
G03X78740Y921260I0J-3937D01*
G01X88582Y925197D02*
G03Y933071I0J3937D01*
G01X82677Y925197D02*
G03X78740Y921260I0J-3937D01*
G01X119291Y933071D02*
X305118D01*
G01X82677Y925197D02*
X755905D01*
G01X82677D02*
X755905D01*
G01X119291D02*
X88582D01*
G01X196089Y-252763D02*
Y-235263D01*
X193469Y-238763D01*
G01Y-252763D02*
X198709D01*
G01X213589Y-235263D02*
X211842Y-235846D01*
X210532Y-237305D01*
X209659Y-239054D01*
X209004Y-241388D01*
X208786Y-244013D01*
X209004Y-246638D01*
X209659Y-248972D01*
X210532Y-250722D01*
X211842Y-252180D01*
X213589Y-252763D01*
X215335Y-252180D01*
X216646Y-250722D01*
X217519Y-248972D01*
X218174Y-246638D01*
X218392Y-244013D01*
X218174Y-241388D01*
X217519Y-239054D01*
X216646Y-237305D01*
X215335Y-235846D01*
X213589Y-235263D01*
G01X227159Y-253346D02*
X235019Y-235263D01*
G01X248589Y-252763D02*
Y-235263D01*
X245969Y-238763D01*
G01Y-252763D02*
X251209D01*
G01X261941Y-245472D02*
X263469Y-243430D01*
X264779Y-242263D01*
X266526Y-241680D01*
X268054Y-242263D01*
X269146Y-243430D01*
X270019Y-245180D01*
X270237Y-247221D01*
X270019Y-248972D01*
X269146Y-250722D01*
X267835Y-252180D01*
X266307Y-252763D01*
X264561Y-252180D01*
X263032Y-250430D01*
X262159Y-247805D01*
X261941Y-244888D01*
X262377Y-241097D01*
X263032Y-239054D01*
X264124Y-237013D01*
X265652Y-235555D01*
X267181Y-235263D01*
X268709Y-235846D01*
X269801Y-237305D01*
G01X279659Y-253346D02*
X287519Y-235263D01*
G01X296941Y-238180D02*
X298251Y-236430D01*
X299779Y-235555D01*
X301526Y-235263D01*
X303709Y-235846D01*
X305237Y-237305D01*
X305674Y-239054D01*
X305456Y-240805D01*
X304582Y-242263D01*
X300216Y-245180D01*
X298251Y-247221D01*
X296941Y-250139D01*
X296504Y-252763D01*
X305674D01*
G01X318589Y-235263D02*
X316842Y-235846D01*
X315532Y-237305D01*
X314659Y-239054D01*
X314004Y-241388D01*
X313786Y-244013D01*
X314004Y-246638D01*
X314659Y-248972D01*
X315532Y-250722D01*
X316842Y-252180D01*
X318589Y-252763D01*
X320335Y-252180D01*
X321646Y-250722D01*
X322519Y-248972D01*
X323174Y-246638D01*
X323392Y-244013D01*
X323174Y-241388D01*
X322519Y-239054D01*
X321646Y-237305D01*
X320335Y-235846D01*
X318589Y-235263D01*
G01X336089Y-252763D02*
Y-235263D01*
X333469Y-238763D01*
G01Y-252763D02*
X338709D01*
G01X349441Y-238180D02*
X350751Y-236430D01*
X352279Y-235555D01*
X354026Y-235263D01*
X356209Y-235846D01*
X357737Y-237305D01*
X358174Y-239054D01*
X357956Y-240805D01*
X357082Y-242263D01*
X352716Y-245180D01*
X350751Y-247221D01*
X349441Y-250139D01*
X349004Y-252763D01*
X358174D01*
G01X243786Y-207763D02*
Y-190263D01*
X248152D01*
X249899Y-191138D01*
X251209Y-192305D01*
X252301Y-194054D01*
X253174Y-196097D01*
X253392Y-199013D01*
X253174Y-201930D01*
X252301Y-203972D01*
X251209Y-205722D01*
X249899Y-206888D01*
X248152Y-207763D01*
X243786D01*
G01X270019D02*
Y-196097D01*
G01Y-198138D02*
X269146Y-196972D01*
X267835Y-196388D01*
X266307Y-196097D01*
X264779Y-196680D01*
X263469Y-197846D01*
X262595Y-199596D01*
X262159Y-201930D01*
X262595Y-204263D01*
X263469Y-206013D01*
X264779Y-207180D01*
X266307Y-207763D01*
X267835Y-207471D01*
X269146Y-206597D01*
X270019Y-205430D01*
G01X283589Y-190263D02*
Y-207763D01*
G01X280532Y-196097D02*
X286646D01*
G01X297814Y-199888D02*
X304801D01*
X304146Y-197846D01*
X303054Y-196680D01*
X301526Y-196097D01*
X299997Y-196388D01*
X298687Y-197263D01*
X297814Y-199305D01*
X297377Y-201055D01*
Y-202805D01*
X297814Y-204555D01*
X298906Y-206305D01*
X300216Y-207471D01*
X301744Y-207763D01*
X303272Y-207180D01*
X304801Y-205430D01*
G01X267716Y-7874D02*
G03Y0I0J3937D01*
G01X298425D02*
X267716D01*
G01X298425D02*
G03Y-7874I0J-3937D01*
G01X483071D02*
X298425D01*
G01X335827Y933071D02*
G03Y925197I0J-3937D01*
G01X305118D02*
G03Y933071I0J3937D01*
G01X335827D02*
X522441D01*
G01X335827Y925197D02*
X305118D01*
G01X483071Y-7874D02*
G03Y0I0J3937D01*
G01X513779D02*
X483071D01*
G01X513779D02*
G03Y-7874I0J-3937D01*
G01X719291D02*
X513779D01*
G01X553149Y933071D02*
G03Y925197I0J-3937D01*
G01X522441D02*
G03Y933071I0J3937D01*
G01X553149D02*
X719291D01*
G01X553149Y925197D02*
X522441D01*
G01X763779Y-7874D02*
G03X767716Y-3937I0J3937D01*
G01X719291Y-7874D02*
G03Y0I0J3937D01*
G01X750000D02*
G03Y-7874I0J-3937D01*
G01X763779D02*
X750000D01*
G01X755905Y0D02*
G03X759842Y3937I0J3937D01*
G01X755905Y0D02*
G03X759842Y3937I0J3937D01*
G01X767716Y185827D02*
Y-3937D01*
G01X759842Y3937D02*
Y324213D01*
G01X750000Y0D02*
X719291D01*
G01X767716Y185827D02*
G03X759842I-3937J0D01*
G01Y216536D02*
Y185827D01*
G01Y216536D02*
G03X767716I3937J0D01*
G01Y316339D02*
Y216536D01*
G01X771653Y320276D02*
G03X767716Y316339I0J-3937D01*
G01X763779Y328150D02*
G03X759842Y324213I0J-3937D01*
G01X793307Y328150D02*
X763779D01*
G01X791338Y320276D02*
X771653D01*
G01X765945Y379725D02*
G03Y372244I0J-3741D01*
G01X793307Y379725D02*
X765945D01*
G01X793307Y372244D02*
X765945D01*
G01X759842Y663977D02*
G03X763779Y660040I3937J0D01*
G01X759842Y663977D02*
Y733662D01*
G01X793307Y660040D02*
X763779D01*
G01Y737599D02*
G03X759842Y733662I0J-3937D01*
G01X793307Y737599D02*
X763779D01*
G01X765945Y789174D02*
G03Y781693I0J-3740D01*
G01X767716Y829331D02*
G03X771653Y825394I3937J0D01*
G01X759842Y821457D02*
G03X763779Y817520I3937J0D01*
G01X767716Y855118D02*
Y829331D01*
G01X759842Y921260D02*
Y821457D01*
G01X771653Y825394D02*
X791338D01*
G01X793307Y817520D02*
X763779D01*
G01X793307Y789174D02*
X765945D01*
G01X793307Y781693D02*
X765945D01*
G01X767716Y855118D02*
G03X759842I-3937J0D01*
G01Y885827D02*
G03X767716I3937J0D01*
G01Y929134D02*
Y885827D01*
G01X759842D02*
Y855118D01*
G01Y921260D02*
G03X755905Y925197I-3937J0D01*
G01X767716Y929134D02*
G03X763779Y933071I-3937J0D01*
G01X750000D02*
G03Y925197I0J-3937D01*
G01X719291D02*
G03Y933071I0J3937D01*
G01X759842Y921260D02*
G03X755905Y925197I-3937J0D01*
G01X750000Y933071D02*
X763779D01*
G01X750000Y925197D02*
X719291D01*
G01X791338Y-35433D02*
G03X795275Y-31496I0J3937D01*
G01D02*
Y316339D01*
G01D02*
G03X791338Y320276I-3937J0D01*
G01X795275Y370276D02*
Y330118D01*
G01D02*
X793307Y328150D01*
G01X795275Y658071D02*
Y381693D01*
G01D02*
X793307Y379725D01*
G01X795275Y370276D02*
X793307Y372244D01*
G01X795275Y658071D02*
X793307Y660040D01*
G01X795275Y779725D02*
Y739567D01*
G01D02*
X793307Y737599D01*
G01X791338Y825394D02*
G03X795275Y829331I0J3937D01*
G01D02*
Y956693D01*
G01Y815552D02*
Y791142D01*
G01Y815552D02*
X793307Y817520D01*
G01X795275Y779725D02*
X793307Y781693D01*
G01X795275Y791142D02*
X793307Y789174D01*
G01X795275Y956693D02*
G03X791338Y960630I-3937J0D01*
M02*
